# T6G (Grand Teton) — schematic netlist excerpt (pin names and nets, part order shuffled) for the footprints in the layout excerpt that follows; sources: Cadence DE-HDL packaged netlist, KiCad conversion of 04192023_DAF0TMB3IC0_F0TG_MB_C_brd_V02_OCP.brd

R4172  Q_RES  33.2 1% CHIP  pkg 0402LF  page 81 : A = GPU_3V3IO_RSVD4_ISO_R ; B = GPU_3V3IO_RSVD4_ISO
C905  Q_CAP_DIFFBUS  DIFF BUS_0.22UF 6.3V 20% X6S  pkg C0201  page 63 : \1\ = P5E_CPU0_P0_TX_C_DP<14> ; \2\ = P5E_CPU0_P0_TX_DP<14>
R4205  Q_RES  1K 1% CHIP  pkg 0402LF  page 235 : A = U271_1_ADD0 ; B = GND

(kicad_pcb
	(version 20260206)
	(generator "pcbnew")
	(generator_version "10.0")
	(general
		(thickness 1.6)
		(legacy_teardrops no)
	)
	(paper "A4")
	(title_block
		(title "04192023_DAF0TMB3IC0_F0TG_MB_C_brd_V02_OCP.brd")
		(comment 1 "Grand Teton / footprints 3961-3963 of 8354")
	)
	(layers
		(0 "F.Cu" signal "TOP")
		(4 "In1.Cu" signal "GND")
		(6 "In2.Cu" signal "IN1")
		(8 "In3.Cu" signal "GND1")
		(10 "In4.Cu" signal "IN2")
		(12 "In5.Cu" signal "GND2")
		(14 "In6.Cu" signal "IN3")
		(16 "In7.Cu" signal "GND3")
		(18 "In8.Cu" signal "VCC")
		(20 "In9.Cu" signal "VCC1")
		(22 "In10.Cu" signal "GND4")
		(24 "In11.Cu" signal "IN4")
		(26 "In12.Cu" signal "GND5")
		(28 "In13.Cu" signal "IN5")
		(30 "In14.Cu" signal "GND6")
		(32 "In15.Cu" signal "IN6")
		(34 "In16.Cu" signal "GND7")
		(2 "B.Cu" signal "BOTTOM")
		(9 "F.Adhes" user "F.Adhesive")
		(11 "B.Adhes" user "B.Adhesive")
		(13 "F.Paste" user "Package Geometry/Pastemask Top")
		(15 "B.Paste" user "Package Geometry/Pastemask Bottom")
		(5 "F.SilkS" user "Ref Des/Silkscreen Top")
		(7 "B.SilkS" user "Ref Des/Silkscreen Bottom")
		(1 "F.Mask" user "Board Geometry/Soldermask Top")
		(3 "B.Mask" user "Board Geometry/Soldermask Bottom")
		(17 "Dwgs.User" user "User.Drawings")
		(19 "Cmts.User" user "User.Comments")
		(21 "Eco1.User" user "User.Eco1")
		(23 "Eco2.User" user "User.Eco2")
		(25 "Edge.Cuts" user "Board Geometry/Outline")
		(27 "Margin" user)
		(31 "F.CrtYd" user "Package Geometry/Place Bound Top")
		(29 "B.CrtYd" user "Package Geometry/Place Bound Bottom")
		(35 "F.Fab" user "Ref Des/Assembly Top")
		(33 "B.Fab" user "Ref Des/Assembly Bottom")
	)
	(footprint ""
		(layer "F.Cu")
		(at 200.952608 -114.641376)
		(property "Reference" "R4172"
			(at 0 0 0)
			(layer "F.SilkS")
			(hide yes)
			(effects
				(font
					(size 1.27 1.27)
				)
			)
		)
		(property "Value" ""
			(at 0 0 0)
			(layer "F.Fab")
			(effects
				(font
					(size 1.27 1.27)
				)
			)
		)
		(duplicate_pad_numbers_are_jumpers no)
		(fp_line
			(start -0.7874 -0.4064)
			(end 0.7874 -0.4064)
			(stroke
				(width 0.1524)
				(type default)
			)
			(layer "F.SilkS")
		)
		(fp_line
			(start -0.7874 0.4064)
			(end -0.7874 -0.4064)
			(stroke
				(width 0.1524)
				(type default)
			)
			(layer "F.SilkS")
		)
		(fp_line
			(start 0.7874 -0.4064)
			(end 0.7874 0.4064)
			(stroke
				(width 0.1524)
				(type default)
			)
			(layer "F.SilkS")
		)
		(fp_line
			(start 0.7874 0.4064)
			(end -0.7874 0.4064)
			(stroke
				(width 0.1524)
				(type default)
			)
			(layer "F.SilkS")
		)
		(fp_line
			(start -0.67945 -0.305054)
			(end -0.12065 -0.305054)
			(stroke
				(width 0.1)
				(type default)
			)
			(layer "F.Fab")
		)
		(fp_line
			(start -0.67945 0.3048)
			(end -0.67945 -0.305054)
			(stroke
				(width 0.1)
				(type default)
			)
			(layer "F.Fab")
		)
		(fp_line
			(start -0.12065 -0.305054)
			(end -0.12065 -0.2794)
			(stroke
				(width 0.1)
				(type default)
			)
			(layer "F.Fab")
		)
		(fp_line
			(start -0.12065 -0.2794)
			(end 0.12065 -0.2794)
			(stroke
				(width 0.1)
				(type default)
			)
			(layer "F.Fab")
		)
		(fp_line
			(start -0.12065 0.2794)
			(end -0.12065 0.3048)
			(stroke
				(width 0.1)
				(type default)
			)
			(layer "F.Fab")
		)
		(fp_line
			(start -0.12065 0.3048)
			(end -0.67945 0.3048)
			(stroke
				(width 0.1)
				(type default)
			)
			(layer "F.Fab")
		)
		(fp_line
			(start 0.120396 0.2794)
			(end -0.12065 0.2794)
			(stroke
				(width 0.1)
				(type default)
			)
			(layer "F.Fab")
		)
		(fp_line
			(start 0.120396 0.3048)
			(end 0.120396 0.2794)
			(stroke
				(width 0.1)
				(type default)
			)
			(layer "F.Fab")
		)
		(fp_line
			(start 0.12065 -0.3048)
			(end 0.67945 -0.3048)
			(stroke
				(width 0.1)
				(type default)
			)
			(layer "F.Fab")
		)
		(fp_line
			(start 0.12065 -0.2794)
			(end 0.12065 -0.3048)
			(stroke
				(width 0.1)
				(type default)
			)
			(layer "F.Fab")
		)
		(fp_line
			(start 0.67945 -0.3048)
			(end 0.67945 0.3048)
			(stroke
				(width 0.1)
				(type default)
			)
			(layer "F.Fab")
		)
		(fp_line
			(start 0.67945 0.3048)
			(end 0.120396 0.3048)
			(stroke
				(width 0.1)
				(type default)
			)
			(layer "F.Fab")
		)
		(pad "1" smd circle
			(at -0.40005 0)
			(size 0 0)
			(layers "F.Cu" "F.Mask" "F.Paste")
			(net "GPU_3V3IO_RSVD4_ISO_R")
		)
		(pad "2" smd circle
			(at 0.40005 0)
			(size 0 0)
			(layers "F.Cu" "F.Mask" "F.Paste")
			(net "GPU_3V3IO_RSVD4_ISO")
		)
	)
	(footprint ""
		(layer "F.Cu")
		(at 303.348898 -15.62481)
		(property "Reference" "R4205"
			(at 0 0 0)
			(layer "F.SilkS")
			(hide yes)
			(effects
				(font
					(size 1.27 1.27)
				)
			)
		)
		(property "Value" ""
			(at 0 0 0)
			(layer "F.Fab")
			(effects
				(font
					(size 1.27 1.27)
				)
			)
		)
		(duplicate_pad_numbers_are_jumpers no)
		(fp_line
			(start -0.7874 -0.4064)
			(end 0.7874 -0.4064)
			(stroke
				(width 0.1524)
				(type default)
			)
			(layer "F.SilkS")
		)
		(fp_line
			(start -0.7874 0.4064)
			(end -0.7874 -0.4064)
			(stroke
				(width 0.1524)
				(type default)
			)
			(layer "F.SilkS")
		)
		(fp_line
			(start 0.7874 -0.4064)
			(end 0.7874 0.4064)
			(stroke
				(width 0.1524)
				(type default)
			)
			(layer "F.SilkS")
		)
		(fp_line
			(start 0.7874 0.4064)
			(end -0.7874 0.4064)
			(stroke
				(width 0.1524)
				(type default)
			)
			(layer "F.SilkS")
		)
		(fp_line
			(start -0.67945 -0.305054)
			(end -0.12065 -0.305054)
			(stroke
				(width 0.1)
				(type default)
			)
			(layer "F.Fab")
		)
		(fp_line
			(start -0.67945 0.3048)
			(end -0.67945 -0.305054)
			(stroke
				(width 0.1)
				(type default)
			)
			(layer "F.Fab")
		)
		(fp_line
			(start -0.12065 -0.305054)
			(end -0.12065 -0.2794)
			(stroke
				(width 0.1)
				(type default)
			)
			(layer "F.Fab")
		)
		(fp_line
			(start -0.12065 -0.2794)
			(end 0.12065 -0.2794)
			(stroke
				(width 0.1)
				(type default)
			)
			(layer "F.Fab")
		)
		(fp_line
			(start -0.12065 0.2794)
			(end -0.12065 0.3048)
			(stroke
				(width 0.1)
				(type default)
			)
			(layer "F.Fab")
		)
		(fp_line
			(start -0.12065 0.3048)
			(end -0.67945 0.3048)
			(stroke
				(width 0.1)
				(type default)
			)
			(layer "F.Fab")
		)
		(fp_line
			(start 0.120396 0.2794)
			(end -0.12065 0.2794)
			(stroke
				(width 0.1)
				(type default)
			)
			(layer "F.Fab")
		)
		(fp_line
			(start 0.120396 0.3048)
			(end 0.120396 0.2794)
			(stroke
				(width 0.1)
				(type default)
			)
			(layer "F.Fab")
		)
		(fp_line
			(start 0.12065 -0.3048)
			(end 0.67945 -0.3048)
			(stroke
				(width 0.1)
				(type default)
			)
			(layer "F.Fab")
		)
		(fp_line
			(start 0.12065 -0.2794)
			(end 0.12065 -0.3048)
			(stroke
				(width 0.1)
				(type default)
			)
			(layer "F.Fab")
		)
		(fp_line
			(start 0.67945 -0.3048)
			(end 0.67945 0.3048)
			(stroke
				(width 0.1)
				(type default)
			)
			(layer "F.Fab")
		)
		(fp_line
			(start 0.67945 0.3048)
			(end 0.120396 0.3048)
			(stroke
				(width 0.1)
				(type default)
			)
			(layer "F.Fab")
		)
		(pad "1" smd circle
			(at -0.40005 0)
			(size 0 0)
			(layers "F.Cu" "F.Mask" "F.Paste")
			(net "U271_1_ADD0")
		)
		(pad "2" smd circle
			(at 0.40005 0)
			(size 0 0)
			(layers "F.Cu" "F.Mask" "F.Paste")
			(net "GND")
		)
	)
	(footprint ""
		(layer "F.Cu")
		(at 325.740776 -384.449828)
		(property "Reference" "C905"
			(at 0 0 0)
			(layer "F.SilkS")
			(hide yes)
			(effects
				(font
					(size 1.27 1.27)
				)
			)
		)
		(property "Value" ""
			(at 0 0 0)
			(layer "F.Fab")
			(effects
				(font
					(size 1.27 1.27)
				)
			)
		)
		(duplicate_pad_numbers_are_jumpers no)
		(fp_line
			(start -0.299974 -0.150114)
			(end 0.299974 -0.150114)
			(stroke
				(width 0.1)
				(type default)
			)
			(layer "F.Fab")
		)
		(fp_line
			(start -0.299974 0.150114)
			(end -0.299974 -0.150114)
			(stroke
				(width 0.1)
				(type default)
			)
			(layer "F.Fab")
		)
		(fp_line
			(start 0.299974 -0.150114)
			(end 0.299974 0.150114)
			(stroke
				(width 0.1)
				(type default)
			)
			(layer "F.Fab")
		)
		(fp_line
			(start 0.299974 0.150114)
			(end -0.299974 0.150114)
			(stroke
				(width 0.1)
				(type default)
			)
			(layer "F.Fab")
		)
		(pad "1" smd rect
			(at -0.2667 0)
			(size 0.3048 0.381)
			(layers "F.Cu" "F.Mask" "F.Paste")
			(net "P5E_CPU0_P0_TX_C_DP<14>")
		)
		(pad "2" smd rect
			(at 0.2667 0)
			(size 0.3048 0.381)
			(layers "F.Cu" "F.Mask" "F.Paste")
			(net "P5E_CPU0_P0_TX_DP<14>")
		)
	)
)
